# BASEBOARD_FAB2 (Tioga Pass) — schematic netlist excerpt (pin names and nets, part order shuffled) for the footprints in the layout excerpt that follows; sources: Cadence DE-HDL packaged netlist, KiCad conversion of Wiwynn_Tioga_Pass_MB.brd

C7B26  CAP  0.22UF 16V 10% X7R  pkg 0402  page 129 : A = DMI_CPU0_PCH_TX_DN<3> ; B = DMI_CPU0_PCH_TX_C_DN<3>
C1E25  CAP  0.22UF 16V 10% X7R  pkg 0402  page 207 : A = P5V_STBY ; B = GND
C4G11  CAP  2200PF 50V 10% X7R  pkg 0402LF  page 233 : A = VR_COMP_PVPP_GHJ ; B = VR_FB_PVPP_GHJ

(kicad_pcb
	(version 20260206)
	(generator "pcbnew")
	(generator_version "10.0")
	(general
		(thickness 1.6)
		(legacy_teardrops no)
	)
	(paper "A4")
	(title_block
		(title "Wiwynn_Tioga_Pass_MB.brd")
		(comment 1 "Tioga Pass / footprints 185-187 of 4770")
	)
	(layers
		(0 "F.Cu" signal "TOP")
		(4 "In1.Cu" signal "L2GND")
		(6 "In2.Cu" signal "L3")
		(8 "In3.Cu" signal "L4GND")
		(10 "In4.Cu" signal "L5")
		(12 "In5.Cu" signal "L6GND")
		(14 "In6.Cu" signal "L7VCC")
		(16 "In7.Cu" signal "L8VCC")
		(18 "In8.Cu" signal "L9GND")
		(20 "In9.Cu" signal "L10")
		(22 "In10.Cu" signal "L11GND")
		(24 "In11.Cu" signal "L12")
		(26 "In12.Cu" signal "L13GND")
		(2 "B.Cu" signal "BOTTOM")
		(9 "F.Adhes" user "F.Adhesive")
		(11 "B.Adhes" user "B.Adhesive")
		(13 "F.Paste" user "Package Geometry/Pastemask Top")
		(15 "B.Paste" user "Package Geometry/Pastemask Bottom")
		(5 "F.SilkS" user "Ref Des/Silkscreen Top")
		(7 "B.SilkS" user "Ref Des/Silkscreen Bottom")
		(1 "F.Mask" user "Board Geometry/Soldermask Top")
		(3 "B.Mask" user "Board Geometry/Soldermask Bottom")
		(17 "Dwgs.User" user "User.Drawings")
		(19 "Cmts.User" user "User.Comments")
		(21 "Eco1.User" user "User.Eco1")
		(23 "Eco2.User" user "User.Eco2")
		(25 "Edge.Cuts" user "Board Geometry/Outline")
		(27 "Margin" user)
		(31 "F.CrtYd" user "Package Geometry/Place Bound Top")
		(29 "B.CrtYd" user "Package Geometry/Place Bound Bottom")
		(35 "F.Fab" user "Ref Des/Assembly Top")
		(33 "B.Fab" user "Ref Des/Assembly Bottom")
	)
	(footprint ""
		(layer "F.Cu")
		(at 33.229296 -61.298582 90)
		(property "Reference" "C1E25"
			(at 0 0 90)
			(layer "F.SilkS")
			(hide yes)
			(effects
				(font
					(size 1.27 1.27)
				)
			)
		)
		(property "Value" ""
			(at 0 0 90)
			(layer "F.Fab")
			(effects
				(font
					(size 1.27 1.27)
				)
			)
		)
		(duplicate_pad_numbers_are_jumpers no)
		(fp_rect
			(start 0.3048 0.9906)
			(end -0.3048 -0.1016)
			(stroke
				(width 0)
				(type default)
			)
			(fill no)
			(layer "F.CrtYd")
		)
		(fp_line
			(start 0.3048 -0.1016)
			(end -0.3048 -0.1016)
			(stroke
				(width 0.1)
				(type default)
			)
			(layer "F.Fab")
		)
		(fp_line
			(start -0.3048 -0.1016)
			(end -0.3048 0.9906)
			(stroke
				(width 0.1)
				(type default)
			)
			(layer "F.Fab")
		)
		(fp_line
			(start 0.3048 0.9906)
			(end 0.3048 -0.1016)
			(stroke
				(width 0.1)
				(type default)
			)
			(layer "F.Fab")
		)
		(fp_line
			(start -0.3048 0.9906)
			(end 0.3048 0.9906)
			(stroke
				(width 0.1)
				(type default)
			)
			(layer "F.Fab")
		)
		(pad "1" smd rect
			(at 0 0 90)
			(size 0.508 0.508)
			(layers "F.Cu" "F.Mask" "F.Paste")
			(net "P5V_STBY")
		)
		(pad "2" smd rect
			(at 0 0.889 90)
			(size 0.508 0.508)
			(layers "F.Cu" "F.Mask" "F.Paste")
			(net "GND")
		)
		(zone
			(layer "F.Cu")
			(hatch none 0.5)
			(connect_pads
				(clearance 0)
			)
			(min_thickness 0.25)
			(keepout
				(tracks not_allowed)
				(vias allowed)
				(pads allowed)
				(copperpour not_allowed)
				(footprints allowed)
			)
			(placement
				(enabled no)
				(sheetname "")
			)
			(fill
				(thermal_gap 0.5)
				(thermal_bridge_width 0.5)
				(island_removal_mode 0)
			)
			(polygon
				(pts
					(xy 33.864296 -61.552582) (xy 33.483296 -61.552582) (xy 33.483296 -61.044582) (xy 33.864296 -61.044582)
				)
			)
		)
		(zone
			(layer "F.Cu")
			(hatch none 0.5)
			(connect_pads
				(clearance 0)
			)
			(min_thickness 0.25)
			(keepout
				(tracks allowed)
				(vias not_allowed)
				(pads allowed)
				(copperpour not_allowed)
				(footprints allowed)
			)
			(placement
				(enabled no)
				(sheetname "")
			)
			(fill
				(thermal_gap 0.5)
				(thermal_bridge_width 0.5)
				(island_removal_mode 0)
			)
			(polygon
				(pts
					(xy 33.864296 -61.552582) (xy 33.483296 -61.552582) (xy 33.483296 -61.044582) (xy 33.864296 -61.044582)
				)
			)
		)
	)
	(footprint ""
		(layer "F.Cu")
		(at 364.617 -113.792 90)
		(property "Reference" "C7B26"
			(at 0 0 90)
			(layer "F.SilkS")
			(hide yes)
			(effects
				(font
					(size 1.27 1.27)
				)
			)
		)
		(property "Value" ""
			(at 0 0 90)
			(layer "F.Fab")
			(effects
				(font
					(size 1.27 1.27)
				)
			)
		)
		(duplicate_pad_numbers_are_jumpers no)
		(fp_poly
			(pts
				(xy 0.3048 -0.1016) (xy 0.3048 0.9906) (xy -0.3048 0.9906) (xy -0.3048 -0.1016)
			)
			(stroke
				(width 0)
				(type default)
			)
			(fill no)
			(layer "F.CrtYd")
		)
		(fp_line
			(start 0.3048 -0.1016)
			(end -0.3048 -0.1016)
			(stroke
				(width 0.1)
				(type default)
			)
			(layer "F.Fab")
		)
		(fp_line
			(start -0.3048 -0.1016)
			(end -0.3048 0.9906)
			(stroke
				(width 0.1)
				(type default)
			)
			(layer "F.Fab")
		)
		(fp_line
			(start 0.3048 0.9906)
			(end 0.3048 -0.1016)
			(stroke
				(width 0.1)
				(type default)
			)
			(layer "F.Fab")
		)
		(fp_line
			(start -0.3048 0.9906)
			(end 0.3048 0.9906)
			(stroke
				(width 0.1)
				(type default)
			)
			(layer "F.Fab")
		)
		(pad "1" smd rect
			(at 0 0 90)
			(size 0.508 0.508)
			(layers "F.Cu" "F.Mask" "F.Paste")
			(net "DMI_CPU0_PCH_TX_DN<3>")
		)
		(pad "2" smd rect
			(at 0 0.889 90)
			(size 0.508 0.508)
			(layers "F.Cu" "F.Mask" "F.Paste")
			(net "DMI_CPU0_PCH_TX_C_DN<3>")
		)
		(zone
			(layer "F.Cu")
			(hatch none 0.5)
			(connect_pads
				(clearance 0)
			)
			(min_thickness 0.25)
			(keepout
				(tracks allowed)
				(vias not_allowed)
				(pads allowed)
				(copperpour not_allowed)
				(footprints allowed)
			)
			(placement
				(enabled no)
				(sheetname "")
			)
			(fill
				(thermal_gap 0.5)
				(thermal_bridge_width 0.5)
				(island_removal_mode 0)
			)
			(polygon
				(pts
					(xy 364.871 -113.538) (xy 364.871 -114.046) (xy 365.252 -114.046) (xy 365.252 -113.538)
				)
			)
		)
		(zone
			(layer "F.Cu")
			(hatch none 0.5)
			(connect_pads
				(clearance 0)
			)
			(min_thickness 0.25)
			(keepout
				(tracks not_allowed)
				(vias allowed)
				(pads allowed)
				(copperpour not_allowed)
				(footprints allowed)
			)
			(placement
				(enabled no)
				(sheetname "")
			)
			(fill
				(thermal_gap 0.5)
				(thermal_bridge_width 0.5)
				(island_removal_mode 0)
			)
			(polygon
				(pts
					(xy 365.252 -113.538) (xy 365.252 -114.046) (xy 364.871 -114.046) (xy 364.871 -113.538)
				)
			)
		)
	)
	(footprint ""
		(layer "F.Cu")
		(at 169.6212 -7.1247 180)
		(property "Reference" "C4G11"
			(at 0 0 180)
			(layer "F.SilkS")
			(hide yes)
			(effects
				(font
					(size 1.27 1.27)
				)
			)
		)
		(property "Value" ""
			(at 0 0 180)
			(layer "F.Fab")
			(effects
				(font
					(size 1.27 1.27)
				)
			)
		)
		(duplicate_pad_numbers_are_jumpers no)
		(fp_poly
			(pts
				(xy 0.3048 -0.1016) (xy 0.3048 0.9906) (xy -0.3048 0.9906) (xy -0.3048 -0.1016)
			)
			(stroke
				(width 0)
				(type default)
			)
			(fill no)
			(layer "F.CrtYd")
		)
		(fp_line
			(start 0.3048 0.9906)
			(end 0.3048 -0.1016)
			(stroke
				(width 0.1)
				(type default)
			)
			(layer "F.Fab")
		)
		(fp_line
			(start 0.3048 -0.1016)
			(end -0.3048 -0.1016)
			(stroke
				(width 0.1)
				(type default)
			)
			(layer "F.Fab")
		)
		(fp_line
			(start -0.3048 0.9906)
			(end 0.3048 0.9906)
			(stroke
				(width 0.1)
				(type default)
			)
			(layer "F.Fab")
		)
		(fp_line
			(start -0.3048 -0.1016)
			(end -0.3048 0.9906)
			(stroke
				(width 0.1)
				(type default)
			)
			(layer "F.Fab")
		)
		(pad "1" smd rect
			(at 0 0 180)
			(size 0.508 0.508)
			(layers "F.Cu" "F.Mask" "F.Paste")
			(net "VR_COMP_PVPP_GHJ")
		)
		(pad "2" smd rect
			(at 0 0.889 180)
			(size 0.508 0.508)
			(layers "F.Cu" "F.Mask" "F.Paste")
			(net "VR_FB_PVPP_GHJ")
		)
		(zone
			(layer "F.Cu")
			(hatch none 0.5)
			(connect_pads
				(clearance 0)
			)
			(min_thickness 0.25)
			(keepout
				(tracks not_allowed)
				(vias allowed)
				(pads allowed)
				(copperpour not_allowed)
				(footprints allowed)
			)
			(placement
				(enabled no)
				(sheetname "")
			)
			(fill
				(thermal_gap 0.5)
				(thermal_bridge_width 0.5)
				(island_removal_mode 0)
			)
			(polygon
				(pts
					(xy 169.8752 -7.7597) (xy 169.3672 -7.7597) (xy 169.3672 -7.3787) (xy 169.8752 -7.3787)
				)
			)
		)
		(zone
			(layer "F.Cu")
			(hatch none 0.5)
			(connect_pads
				(clearance 0)
			)
			(min_thickness 0.25)
			(keepout
				(tracks allowed)
				(vias not_allowed)
				(pads allowed)
				(copperpour not_allowed)
				(footprints allowed)
			)
			(placement
				(enabled no)
				(sheetname "")
			)
			(fill
				(thermal_gap 0.5)
				(thermal_bridge_width 0.5)
				(island_removal_mode 0)
			)
			(polygon
				(pts
					(xy 169.8752 -7.3787) (xy 169.3672 -7.3787) (xy 169.3672 -7.7597) (xy 169.8752 -7.7597)
				)
			)
		)
	)
)
